# T6G (Grand Teton) — schematic netlist excerpt (pin names and nets, part order shuffled) for the footprints in the layout excerpt that follows; sources: Cadence DE-HDL packaged netlist, KiCad conversion of 04192023_DAF0TMB3IC0_F0TG_MB_C_brd_V02_OCP.brd

R3505  Q_RES  33.2 1% CHIP  pkg 0402LF  page 81 : A = GPU_FPGA_EROT_FATALERR_ISO_R_N ; B = GPU_FPGA_EROT_FATALERR_ISO_N
R43  Q_RES  4.7K 5% EMPTY  pkg 0402LF  page 238 : A = P3V3_AUX ; B = SMB_FRU_3V3AUX_R1_SDA

(kicad_pcb
	(version 20260206)
	(generator "pcbnew")
	(generator_version "10.0")
	(general
		(thickness 1.6)
		(legacy_teardrops no)
	)
	(paper "A4")
	(title_block
		(title "04192023_DAF0TMB3IC0_F0TG_MB_C_brd_V02_OCP.brd")
		(comment 1 "Grand Teton / footprints 4682-4683 of 8354")
	)
	(layers
		(0 "F.Cu" signal "TOP")
		(4 "In1.Cu" signal "GND")
		(6 "In2.Cu" signal "IN1")
		(8 "In3.Cu" signal "GND1")
		(10 "In4.Cu" signal "IN2")
		(12 "In5.Cu" signal "GND2")
		(14 "In6.Cu" signal "IN3")
		(16 "In7.Cu" signal "GND3")
		(18 "In8.Cu" signal "VCC")
		(20 "In9.Cu" signal "VCC1")
		(22 "In10.Cu" signal "GND4")
		(24 "In11.Cu" signal "IN4")
		(26 "In12.Cu" signal "GND5")
		(28 "In13.Cu" signal "IN5")
		(30 "In14.Cu" signal "GND6")
		(32 "In15.Cu" signal "IN6")
		(34 "In16.Cu" signal "GND7")
		(2 "B.Cu" signal "BOTTOM")
		(9 "F.Adhes" user "F.Adhesive")
		(11 "B.Adhes" user "B.Adhesive")
		(13 "F.Paste" user "Package Geometry/Pastemask Top")
		(15 "B.Paste" user "Package Geometry/Pastemask Bottom")
		(5 "F.SilkS" user "Ref Des/Silkscreen Top")
		(7 "B.SilkS" user "Ref Des/Silkscreen Bottom")
		(1 "F.Mask" user "Board Geometry/Soldermask Top")
		(3 "B.Mask" user "Board Geometry/Soldermask Bottom")
		(17 "Dwgs.User" user "User.Drawings")
		(19 "Cmts.User" user "User.Comments")
		(21 "Eco1.User" user "User.Eco1")
		(23 "Eco2.User" user "User.Eco2")
		(25 "Edge.Cuts" user "Board Geometry/Outline")
		(27 "Margin" user)
		(31 "F.CrtYd" user "Package Geometry/Place Bound Top")
		(29 "B.CrtYd" user "Package Geometry/Place Bound Bottom")
		(35 "F.Fab" user "Ref Des/Assembly Top")
		(33 "B.Fab" user "Ref Des/Assembly Bottom")
	)
	(footprint ""
		(layer "F.Cu")
		(at 320.171318 -115.410488 180)
		(property "Reference" "R43"
			(at 0 0 180)
			(layer "F.SilkS")
			(hide yes)
			(effects
				(font
					(size 1.27 1.27)
				)
			)
		)
		(property "Value" ""
			(at 0 0 180)
			(layer "F.Fab")
			(effects
				(font
					(size 1.27 1.27)
				)
			)
		)
		(duplicate_pad_numbers_are_jumpers no)
		(fp_line
			(start 0.7874 0.4064)
			(end -0.7874 0.4064)
			(stroke
				(width 0.1524)
				(type default)
			)
			(layer "F.SilkS")
		)
		(fp_line
			(start 0.7874 -0.4064)
			(end 0.7874 0.4064)
			(stroke
				(width 0.1524)
				(type default)
			)
			(layer "F.SilkS")
		)
		(fp_line
			(start -0.7874 0.4064)
			(end -0.7874 -0.4064)
			(stroke
				(width 0.1524)
				(type default)
			)
			(layer "F.SilkS")
		)
		(fp_line
			(start -0.7874 -0.4064)
			(end 0.7874 -0.4064)
			(stroke
				(width 0.1524)
				(type default)
			)
			(layer "F.SilkS")
		)
		(fp_line
			(start 0.67945 0.3048)
			(end 0.120396 0.3048)
			(stroke
				(width 0.1)
				(type default)
			)
			(layer "F.Fab")
		)
		(fp_line
			(start 0.67945 -0.3048)
			(end 0.67945 0.3048)
			(stroke
				(width 0.1)
				(type default)
			)
			(layer "F.Fab")
		)
		(fp_line
			(start 0.12065 -0.2794)
			(end 0.12065 -0.3048)
			(stroke
				(width 0.1)
				(type default)
			)
			(layer "F.Fab")
		)
		(fp_line
			(start 0.12065 -0.3048)
			(end 0.67945 -0.3048)
			(stroke
				(width 0.1)
				(type default)
			)
			(layer "F.Fab")
		)
		(fp_line
			(start 0.120396 0.3048)
			(end 0.120396 0.2794)
			(stroke
				(width 0.1)
				(type default)
			)
			(layer "F.Fab")
		)
		(fp_line
			(start 0.120396 0.2794)
			(end -0.12065 0.2794)
			(stroke
				(width 0.1)
				(type default)
			)
			(layer "F.Fab")
		)
		(fp_line
			(start -0.12065 0.3048)
			(end -0.67945 0.3048)
			(stroke
				(width 0.1)
				(type default)
			)
			(layer "F.Fab")
		)
		(fp_line
			(start -0.12065 0.2794)
			(end -0.12065 0.3048)
			(stroke
				(width 0.1)
				(type default)
			)
			(layer "F.Fab")
		)
		(fp_line
			(start -0.12065 -0.2794)
			(end 0.12065 -0.2794)
			(stroke
				(width 0.1)
				(type default)
			)
			(layer "F.Fab")
		)
		(fp_line
			(start -0.12065 -0.305054)
			(end -0.12065 -0.2794)
			(stroke
				(width 0.1)
				(type default)
			)
			(layer "F.Fab")
		)
		(fp_line
			(start -0.67945 0.3048)
			(end -0.67945 -0.305054)
			(stroke
				(width 0.1)
				(type default)
			)
			(layer "F.Fab")
		)
		(fp_line
			(start -0.67945 -0.305054)
			(end -0.12065 -0.305054)
			(stroke
				(width 0.1)
				(type default)
			)
			(layer "F.Fab")
		)
		(pad "1" smd circle
			(at -0.40005 0 180)
			(size 0 0)
			(layers "F.Cu" "F.Mask" "F.Paste")
			(net "P3V3_AUX")
		)
		(pad "2" smd circle
			(at 0.40005 0 180)
			(size 0 0)
			(layers "F.Cu" "F.Mask" "F.Paste")
			(net "SMB_FRU_3V3AUX_R1_SDA")
		)
	)
	(footprint ""
		(layer "F.Cu")
		(at 208.878932 -118.762272)
		(property "Reference" "R3505"
			(at 0 0 0)
			(layer "F.SilkS")
			(hide yes)
			(effects
				(font
					(size 1.27 1.27)
				)
			)
		)
		(property "Value" ""
			(at 0 0 0)
			(layer "F.Fab")
			(effects
				(font
					(size 1.27 1.27)
				)
			)
		)
		(duplicate_pad_numbers_are_jumpers no)
		(fp_line
			(start -0.7874 -0.4064)
			(end 0.7874 -0.4064)
			(stroke
				(width 0.1524)
				(type default)
			)
			(layer "F.SilkS")
		)
		(fp_line
			(start -0.7874 0.4064)
			(end -0.7874 -0.4064)
			(stroke
				(width 0.1524)
				(type default)
			)
			(layer "F.SilkS")
		)
		(fp_line
			(start 0.7874 -0.4064)
			(end 0.7874 0.4064)
			(stroke
				(width 0.1524)
				(type default)
			)
			(layer "F.SilkS")
		)
		(fp_line
			(start 0.7874 0.4064)
			(end -0.7874 0.4064)
			(stroke
				(width 0.1524)
				(type default)
			)
			(layer "F.SilkS")
		)
		(fp_line
			(start -0.67945 -0.305054)
			(end -0.12065 -0.305054)
			(stroke
				(width 0.1)
				(type default)
			)
			(layer "F.Fab")
		)
		(fp_line
			(start -0.67945 0.3048)
			(end -0.67945 -0.305054)
			(stroke
				(width 0.1)
				(type default)
			)
			(layer "F.Fab")
		)
		(fp_line
			(start -0.12065 -0.305054)
			(end -0.12065 -0.2794)
			(stroke
				(width 0.1)
				(type default)
			)
			(layer "F.Fab")
		)
		(fp_line
			(start -0.12065 -0.2794)
			(end 0.12065 -0.2794)
			(stroke
				(width 0.1)
				(type default)
			)
			(layer "F.Fab")
		)
		(fp_line
			(start -0.12065 0.2794)
			(end -0.12065 0.3048)
			(stroke
				(width 0.1)
				(type default)
			)
			(layer "F.Fab")
		)
		(fp_line
			(start -0.12065 0.3048)
			(end -0.67945 0.3048)
			(stroke
				(width 0.1)
				(type default)
			)
			(layer "F.Fab")
		)
		(fp_line
			(start 0.120396 0.2794)
			(end -0.12065 0.2794)
			(stroke
				(width 0.1)
				(type default)
			)
			(layer "F.Fab")
		)
		(fp_line
			(start 0.120396 0.3048)
			(end 0.120396 0.2794)
			(stroke
				(width 0.1)
				(type default)
			)
			(layer "F.Fab")
		)
		(fp_line
			(start 0.12065 -0.3048)
			(end 0.67945 -0.3048)
			(stroke
				(width 0.1)
				(type default)
			)
			(layer "F.Fab")
		)
		(fp_line
			(start 0.12065 -0.2794)
			(end 0.12065 -0.3048)
			(stroke
				(width 0.1)
				(type default)
			)
			(layer "F.Fab")
		)
		(fp_line
			(start 0.67945 -0.3048)
			(end 0.67945 0.3048)
			(stroke
				(width 0.1)
				(type default)
			)
			(layer "F.Fab")
		)
		(fp_line
			(start 0.67945 0.3048)
			(end 0.120396 0.3048)
			(stroke
				(width 0.1)
				(type default)
			)
			(layer "F.Fab")
		)
		(pad "1" smd circle
			(at -0.40005 0)
			(size 0 0)
			(layers "F.Cu" "F.Mask" "F.Paste")
			(net "GPU_FPGA_EROT_FATALERR_ISO_R_N")
		)
		(pad "2" smd circle
			(at 0.40005 0)
			(size 0 0)
			(layers "F.Cu" "F.Mask" "F.Paste")
			(net "GPU_FPGA_EROT_FATALERR_ISO_N")
		)
	)
)
